FILE_TYPE=LIBRARY_PARTS;
primitive 'ADM4073', 'ADM4073_SM';
  pin
    'GND'<1>:
      PIN_NUMBER='(2)';
      PINUSE='GROUND';
      NO_LOAD_CHECK='Both';
      NO_IO_CHECK='Both';
      NO_ASSERT_CHECK='TRUE';
      NO_DIR_CHECK='TRUE';
      ALLOW_CONNECT='TRUE';
    'GND'<0>:
      PIN_NUMBER='(1)';
      PINUSE='GROUND';
      NO_LOAD_CHECK='Both';
      NO_IO_CHECK='Both';
      NO_ASSERT_CHECK='TRUE';
      NO_DIR_CHECK='TRUE';
      ALLOW_CONNECT='TRUE';
    'OUT':
      PIN_NUMBER='(6)';
      OUTPUT_LOAD='(1.0,-1.0)';
    'RSN':
      PIN_NUMBER='(5)';
      BIDIRECTIONAL='TRUE';
      INPUT_LOAD='(-0.01,0.01)';
      OUTPUT_LOAD='(1.0,-1.0)';
    'RSP':
      PIN_NUMBER='(4)';
      BIDIRECTIONAL='TRUE';
      INPUT_LOAD='(-0.01,0.01)';
      OUTPUT_LOAD='(1.0,-1.0)';
    'VCC':
      PIN_NUMBER='(3)';
      PINUSE='POWER';
      NO_LOAD_CHECK='Both';
      NO_IO_CHECK='Both';
      NO_ASSERT_CHECK='TRUE';
      NO_DIR_CHECK='TRUE';
      ALLOW_CONNECT='TRUE';
  end_pin;
  body
    PART_NAME='ADM4073';
    PHYS_DES_PREFIX='U';
  end_body;
end_primitive;

END.
